(kicad_pcb
	(version 20260206)
	(generator "pcbnew")
	(generator_version "10.0")
	(general
		(thickness 1.6)
		(legacy_teardrops no)
	)
	(paper "A4")
	(title_block
		(title "Bryce Canyon_SCC_16316-1_OCP.brd")
		(comment 1 "Bryce Canyon / footprints 1120-1127 of 1561")
	)
	(layers
		(0 "F.Cu" signal "TOP")
		(4 "In1.Cu" signal "L2GND")
		(6 "In2.Cu" signal "L3")
		(8 "In3.Cu" signal "L4VCC")
		(10 "In4.Cu" signal "L5VCC")
		(12 "In5.Cu" signal "L6")
		(14 "In6.Cu" signal "L7GND")
		(2 "B.Cu" signal "BOTTOM")
		(9 "F.Adhes" user "F.Adhesive")
		(11 "B.Adhes" user "B.Adhesive")
		(13 "F.Paste" user "Package Geometry/Pastemask Top")
		(15 "B.Paste" user "Package Geometry/Pastemask Bottom")
		(5 "F.SilkS" user "Ref Des/Silkscreen Top")
		(7 "B.SilkS" user "Ref Des/Silkscreen Bottom")
		(1 "F.Mask" user "Board Geometry/Soldermask Top")
		(3 "B.Mask" user "Board Geometry/Soldermask Bottom")
		(17 "Dwgs.User" user "User.Drawings")
		(19 "Cmts.User" user "User.Comments")
		(21 "Eco1.User" user "User.Eco1")
		(23 "Eco2.User" user "User.Eco2")
		(25 "Edge.Cuts" user "Board Geometry/Outline")
		(27 "Margin" user)
		(31 "F.CrtYd" user "Package Geometry/Place Bound Top")
		(29 "B.CrtYd" user "Package Geometry/Place Bound Bottom")
		(35 "F.Fab" user "Ref Des/Assembly Top")
		(33 "B.Fab" user "Ref Des/Assembly Bottom")
	)
	(footprint ""
		(layer "B.Cu")
		(at 133.2738 -44.3992 180)
		(property "Reference" "C28"
			(at 0 0 0)
			(layer "B.SilkS")
			(hide yes)
			(effects
				(font
					(size 1.27 1.27)
				)
				(justify mirror)
			)
		)
		(property "Value" "SCD01U16V1KX-GP"
			(at 2.8321 -1.7399 180)
			(unlocked yes)
			(layer "B.Fab")
			(hide yes)
			(effects
				(font
					(size 1.016 1.016)
					(thickness 0.1524)
				)
				(justify mirror)
			)
		)
		(property "Device Type" "C0201H13"
			(at 2.8321 -3.2639 180)
			(unlocked yes)
			(layer "B.Fab")
			(hide yes)
			(effects
				(font
					(size 1.016 1.016)
					(thickness 0.1524)
				)
				(justify mirror)
			)
		)
		(duplicate_pad_numbers_are_jumpers no)
		(fp_rect
			(start 0.2794 0.6477)
			(end -0.2794 -0.6477)
			(stroke
				(width 0)
				(type default)
			)
			(fill no)
			(layer "B.CrtYd")
		)
		(fp_rect
			(start 0.2794 0.6477)
			(end -0.2794 -0.6477)
			(stroke
				(width 0)
				(type default)
			)
			(fill no)
			(layer "B.Fab")
		)
		(pad "1" smd custom
			(at 0 -0.2794)
			(size 0.0762 0.0762)
			(layers "B.Cu" "B.Mask" "B.Paste")
			(net "PHY_DPB_TO_SCC_30_DN")
			(options
				(clearance outline)
				(anchor circle)
			)
			(primitives
				(gr_poly
					(pts
						(arc
							(start 0.1524 0.127)
							(mid 0.137521 0.162921)
							(end 0.1016 0.1778)
						)
						(arc
							(start -0.1016 0.1778)
							(mid -0.137521 0.162921)
							(end -0.1524 0.127)
						)
						(arc
							(start -0.1524 -0.127)
							(mid -0.137521 -0.162921)
							(end -0.1016 -0.1778)
						)
						(arc
							(start 0.1016 -0.1778)
							(mid 0.137521 -0.162921)
							(end 0.1524 -0.127)
						)
					)
					(width 0)
					(fill yes)
				)
			)
		)
		(pad "2" smd custom
			(at 0 0.2794)
			(size 0.0762 0.0762)
			(layers "B.Cu" "B.Mask" "B.Paste")
			(net "PHY_DPB_TO_SCC_C_30_DN")
			(options
				(clearance outline)
				(anchor circle)
			)
			(primitives
				(gr_poly
					(pts
						(arc
							(start 0.1524 0.127)
							(mid 0.137521 0.162921)
							(end 0.1016 0.1778)
						)
						(arc
							(start -0.1016 0.1778)
							(mid -0.137521 0.162921)
							(end -0.1524 0.127)
						)
						(arc
							(start -0.1524 -0.127)
							(mid -0.137521 -0.162921)
							(end -0.1016 -0.1778)
						)
						(arc
							(start 0.1016 -0.1778)
							(mid 0.137521 -0.162921)
							(end 0.1524 -0.127)
						)
					)
					(width 0)
					(fill yes)
				)
			)
		)
	)
	(footprint ""
		(layer "B.Cu")
		(at 170.484038 -32.785304 90)
		(property "Reference" "C393"
			(at 0 0 90)
			(layer "B.SilkS")
			(hide yes)
			(effects
				(font
					(size 1.27 1.27)
				)
				(justify mirror)
			)
		)
		(property "Value" "SCD1U6D3V1KX-GP"
			(at 2.8321 -1.7399 90)
			(unlocked yes)
			(layer "B.Fab")
			(hide yes)
			(effects
				(font
					(size 1.016 1.016)
					(thickness 0.1524)
				)
				(justify mirror)
			)
		)
		(property "Device Type" "C0201H13"
			(at 2.8321 -3.2639 90)
			(unlocked yes)
			(layer "B.Fab")
			(hide yes)
			(effects
				(font
					(size 1.016 1.016)
					(thickness 0.1524)
				)
				(justify mirror)
			)
		)
		(duplicate_pad_numbers_are_jumpers no)
		(fp_rect
			(start 0.2794 0.6477)
			(end -0.2794 -0.6477)
			(stroke
				(width 0)
				(type default)
			)
			(fill no)
			(layer "B.CrtYd")
		)
		(fp_rect
			(start 0.2794 0.6477)
			(end -0.2794 -0.6477)
			(stroke
				(width 0)
				(type default)
			)
			(fill no)
			(layer "B.Fab")
		)
		(pad "1" smd custom
			(at 0 -0.2794 270)
			(size 0.0762 0.0762)
			(layers "B.Cu" "B.Mask" "B.Paste")
			(net "PCE_AVDD")
			(options
				(clearance outline)
				(anchor circle)
			)
			(primitives
				(gr_poly
					(pts
						(arc
							(start 0.1524 0.127)
							(mid 0.137521 0.162921)
							(end 0.1016 0.1778)
						)
						(arc
							(start -0.1016 0.1778)
							(mid -0.137521 0.162921)
							(end -0.1524 0.127)
						)
						(arc
							(start -0.1524 -0.127)
							(mid -0.137521 -0.162921)
							(end -0.1016 -0.1778)
						)
						(arc
							(start 0.1016 -0.1778)
							(mid 0.137521 -0.162921)
							(end 0.1524 -0.127)
						)
					)
					(width 0)
					(fill yes)
				)
			)
		)
		(pad "2" smd custom
			(at 0 0.2794 270)
			(size 0.0762 0.0762)
			(layers "B.Cu" "B.Mask" "B.Paste")
			(net "GND")
			(options
				(clearance outline)
				(anchor circle)
			)
			(primitives
				(gr_poly
					(pts
						(arc
							(start 0.1524 0.127)
							(mid 0.137521 0.162921)
							(end 0.1016 0.1778)
						)
						(arc
							(start -0.1016 0.1778)
							(mid -0.137521 0.162921)
							(end -0.1524 0.127)
						)
						(arc
							(start -0.1524 -0.127)
							(mid -0.137521 -0.162921)
							(end -0.1016 -0.1778)
						)
						(arc
							(start 0.1016 -0.1778)
							(mid 0.137521 -0.162921)
							(end 0.1524 -0.127)
						)
					)
					(width 0)
					(fill yes)
				)
			)
		)
	)
	(footprint ""
		(layer "B.Cu")
		(at 153.803604 -66.916808 180)
		(property "Reference" "L20"
			(at 0 0 0)
			(layer "B.SilkS")
			(hide yes)
			(effects
				(font
					(size 1.27 1.27)
				)
				(justify mirror)
			)
		)
		(property "Value" "MPZ2012S601AT-GP"
			(at 0 -4.2418 180)
			(unlocked yes)
			(layer "B.Fab")
			(hide yes)
			(effects
				(font
					(size 1.016 1.016)
					(thickness 0.1524)
				)
				(justify mirror)
			)
		)
		(property "Device Type" "L805H42"
			(at 0 -5.7912 180)
			(unlocked yes)
			(layer "B.Fab")
			(hide yes)
			(effects
				(font
					(size 1.016 1.016)
					(thickness 0.1524)
				)
				(justify mirror)
			)
		)
		(duplicate_pad_numbers_are_jumpers no)
		(fp_line
			(start 0.889 1.7018)
			(end 0.889 -1.7018)
			(stroke
				(width 0.1524)
				(type default)
			)
			(layer "B.SilkS")
		)
		(fp_line
			(start 0.889 -1.7018)
			(end -0.889 -1.7018)
			(stroke
				(width 0.1524)
				(type default)
			)
			(layer "B.SilkS")
		)
		(fp_line
			(start -0.889 1.7018)
			(end 0.889 1.7018)
			(stroke
				(width 0.1524)
				(type default)
			)
			(layer "B.SilkS")
		)
		(fp_line
			(start -0.889 -1.7018)
			(end -0.889 1.7018)
			(stroke
				(width 0.1524)
				(type default)
			)
			(layer "B.SilkS")
		)
		(fp_rect
			(start 0.9652 1.778)
			(end -0.9652 -1.778)
			(stroke
				(width 0)
				(type default)
			)
			(fill no)
			(layer "B.CrtYd")
		)
		(fp_rect
			(start 0.9652 1.778)
			(end -0.9652 -1.778)
			(stroke
				(width 0)
				(type default)
			)
			(fill no)
			(layer "B.Fab")
		)
		(pad "1" smd rect
			(at 0 -0.9652)
			(size 1.397 1.143)
			(layers "B.Cu" "B.Mask" "B.Paste")
			(net "SYS_PLL_VDD")
		)
		(pad "2" smd rect
			(at 0 0.9652)
			(size 1.397 1.143)
			(layers "B.Cu" "B.Mask" "B.Paste")
			(net "P1V8_C")
		)
	)
	(footprint ""
		(layer "B.Cu")
		(at 137.4648 -71.4502 -90)
		(property "Reference" "C13"
			(at 0 0 90)
			(layer "B.SilkS")
			(hide yes)
			(effects
				(font
					(size 1.27 1.27)
				)
				(justify mirror)
			)
		)
		(property "Value" "SCD01U16V1KX-GP"
			(at 2.8321 -1.7399 270)
			(unlocked yes)
			(layer "B.Fab")
			(hide yes)
			(effects
				(font
					(size 1.016 1.016)
					(thickness 0.1524)
				)
				(justify mirror)
			)
		)
		(property "Device Type" "C0201H13"
			(at 2.8321 -3.2639 270)
			(unlocked yes)
			(layer "B.Fab")
			(hide yes)
			(effects
				(font
					(size 1.016 1.016)
					(thickness 0.1524)
				)
				(justify mirror)
			)
		)
		(duplicate_pad_numbers_are_jumpers no)
		(fp_rect
			(start 0.2794 0.6477)
			(end -0.2794 -0.6477)
			(stroke
				(width 0)
				(type default)
			)
			(fill no)
			(layer "B.CrtYd")
		)
		(fp_rect
			(start 0.2794 0.6477)
			(end -0.2794 -0.6477)
			(stroke
				(width 0)
				(type default)
			)
			(fill no)
			(layer "B.Fab")
		)
		(pad "1" smd custom
			(at 0 -0.2794 90)
			(size 0.0762 0.0762)
			(layers "B.Cu" "B.Mask" "B.Paste")
			(net "PHY_DPB_TO_SCC_5_DP")
			(options
				(clearance outline)
				(anchor circle)
			)
			(primitives
				(gr_poly
					(pts
						(arc
							(start 0.1524 0.127)
							(mid 0.137521 0.162921)
							(end 0.1016 0.1778)
						)
						(arc
							(start -0.1016 0.1778)
							(mid -0.137521 0.162921)
							(end -0.1524 0.127)
						)
						(arc
							(start -0.1524 -0.127)
							(mid -0.137521 -0.162921)
							(end -0.1016 -0.1778)
						)
						(arc
							(start 0.1016 -0.1778)
							(mid 0.137521 -0.162921)
							(end 0.1524 -0.127)
						)
					)
					(width 0)
					(fill yes)
				)
			)
		)
		(pad "2" smd custom
			(at 0 0.2794 90)
			(size 0.0762 0.0762)
			(layers "B.Cu" "B.Mask" "B.Paste")
			(net "PHY_DPB_TO_SCC_C_5_DP")
			(options
				(clearance outline)
				(anchor circle)
			)
			(primitives
				(gr_poly
					(pts
						(arc
							(start 0.1524 0.127)
							(mid 0.137521 0.162921)
							(end 0.1016 0.1778)
						)
						(arc
							(start -0.1016 0.1778)
							(mid -0.137521 0.162921)
							(end -0.1524 0.127)
						)
						(arc
							(start -0.1524 -0.127)
							(mid -0.137521 -0.162921)
							(end -0.1016 -0.1778)
						)
						(arc
							(start 0.1016 -0.1778)
							(mid 0.137521 -0.162921)
							(end 0.1524 -0.127)
						)
					)
					(width 0)
					(fill yes)
				)
			)
		)
	)
	(footprint ""
		(layer "B.Cu")
		(at 114.935 -44.2214 180)
		(property "Reference" "C64"
			(at 0 0 0)
			(layer "B.SilkS")
			(hide yes)
			(effects
				(font
					(size 1.27 1.27)
				)
				(justify mirror)
			)
		)
		(property "Value" "SCD01U16V1KX-GP"
			(at 2.8321 -1.7399 180)
			(unlocked yes)
			(layer "B.Fab")
			(hide yes)
			(effects
				(font
					(size 1.016 1.016)
					(thickness 0.1524)
				)
				(justify mirror)
			)
		)
		(property "Device Type" "C0201H13"
			(at 2.8321 -3.2639 180)
			(unlocked yes)
			(layer "B.Fab")
			(hide yes)
			(effects
				(font
					(size 1.016 1.016)
					(thickness 0.1524)
				)
				(justify mirror)
			)
		)
		(duplicate_pad_numbers_are_jumpers no)
		(fp_rect
			(start 0.2794 0.6477)
			(end -0.2794 -0.6477)
			(stroke
				(width 0)
				(type default)
			)
			(fill no)
			(layer "B.CrtYd")
		)
		(fp_rect
			(start 0.2794 0.6477)
			(end -0.2794 -0.6477)
			(stroke
				(width 0)
				(type default)
			)
			(fill no)
			(layer "B.Fab")
		)
		(pad "1" smd custom
			(at 0 -0.2794)
			(size 0.0762 0.0762)
			(layers "B.Cu" "B.Mask" "B.Paste")
			(net "PHY_DPB_TO_SCC_32_DN")
			(options
				(clearance outline)
				(anchor circle)
			)
			(primitives
				(gr_poly
					(pts
						(arc
							(start 0.1524 0.127)
							(mid 0.137521 0.162921)
							(end 0.1016 0.1778)
						)
						(arc
							(start -0.1016 0.1778)
							(mid -0.137521 0.162921)
							(end -0.1524 0.127)
						)
						(arc
							(start -0.1524 -0.127)
							(mid -0.137521 -0.162921)
							(end -0.1016 -0.1778)
						)
						(arc
							(start 0.1016 -0.1778)
							(mid 0.137521 -0.162921)
							(end 0.1524 -0.127)
						)
					)
					(width 0)
					(fill yes)
				)
			)
		)
		(pad "2" smd custom
			(at 0 0.2794)
			(size 0.0762 0.0762)
			(layers "B.Cu" "B.Mask" "B.Paste")
			(net "PHY_DPB_TO_SCC_C_32_DN")
			(options
				(clearance outline)
				(anchor circle)
			)
			(primitives
				(gr_poly
					(pts
						(arc
							(start 0.1524 0.127)
							(mid 0.137521 0.162921)
							(end 0.1016 0.1778)
						)
						(arc
							(start -0.1016 0.1778)
							(mid -0.137521 0.162921)
							(end -0.1524 0.127)
						)
						(arc
							(start -0.1524 -0.127)
							(mid -0.137521 -0.162921)
							(end -0.1016 -0.1778)
						)
						(arc
							(start 0.1016 -0.1778)
							(mid 0.137521 -0.162921)
							(end 0.1524 -0.127)
						)
					)
					(width 0)
					(fill yes)
				)
			)
		)
	)
	(footprint ""
		(layer "B.Cu")
		(at 106.8578 -57.4802)
		(property "Reference" "C581"
			(at 0 0 0)
			(layer "B.SilkS")
			(hide yes)
			(effects
				(font
					(size 1.27 1.27)
				)
				(justify mirror)
			)
		)
		(property "Value" "SCD1U6D3V1KX-GP"
			(at 2.8321 -1.7399 0)
			(unlocked yes)
			(layer "B.Fab")
			(hide yes)
			(effects
				(font
					(size 1.016 1.016)
					(thickness 0.1524)
				)
				(justify mirror)
			)
		)
		(property "Device Type" "C0201H13"
			(at 2.8321 -3.2639 0)
			(unlocked yes)
			(layer "B.Fab")
			(hide yes)
			(effects
				(font
					(size 1.016 1.016)
					(thickness 0.1524)
				)
				(justify mirror)
			)
		)
		(duplicate_pad_numbers_are_jumpers no)
		(fp_rect
			(start 0.2794 0.6477)
			(end -0.2794 -0.6477)
			(stroke
				(width 0)
				(type default)
			)
			(fill no)
			(layer "B.CrtYd")
		)
		(fp_rect
			(start 0.2794 0.6477)
			(end -0.2794 -0.6477)
			(stroke
				(width 0)
				(type default)
			)
			(fill no)
			(layer "B.Fab")
		)
		(pad "1" smd custom
			(at 0 -0.2794 180)
			(size 0.0762 0.0762)
			(layers "B.Cu" "B.Mask" "B.Paste")
			(net "GB_VDDA")
			(options
				(clearance outline)
				(anchor circle)
			)
			(primitives
				(gr_poly
					(pts
						(arc
							(start 0.1524 0.127)
							(mid 0.137521 0.162921)
							(end 0.1016 0.1778)
						)
						(arc
							(start -0.1016 0.1778)
							(mid -0.137521 0.162921)
							(end -0.1524 0.127)
						)
						(arc
							(start -0.1524 -0.127)
							(mid -0.137521 -0.162921)
							(end -0.1016 -0.1778)
						)
						(arc
							(start 0.1016 -0.1778)
							(mid 0.137521 -0.162921)
							(end 0.1524 -0.127)
						)
					)
					(width 0)
					(fill yes)
				)
			)
		)
		(pad "2" smd custom
			(at 0 0.2794 180)
			(size 0.0762 0.0762)
			(layers "B.Cu" "B.Mask" "B.Paste")
			(net "GND")
			(options
				(clearance outline)
				(anchor circle)
			)
			(primitives
				(gr_poly
					(pts
						(arc
							(start 0.1524 0.127)
							(mid 0.137521 0.162921)
							(end 0.1016 0.1778)
						)
						(arc
							(start -0.1016 0.1778)
							(mid -0.137521 0.162921)
							(end -0.1524 0.127)
						)
						(arc
							(start -0.1524 -0.127)
							(mid -0.137521 -0.162921)
							(end -0.1016 -0.1778)
						)
						(arc
							(start 0.1016 -0.1778)
							(mid 0.137521 -0.162921)
							(end 0.1524 -0.127)
						)
					)
					(width 0)
					(fill yes)
				)
			)
		)
	)
	(footprint ""
		(layer "B.Cu")
		(at 137.4648 -66.2686 -90)
		(property "Reference" "C20"
			(at 0 0 90)
			(layer "B.SilkS")
			(hide yes)
			(effects
				(font
					(size 1.27 1.27)
				)
				(justify mirror)
			)
		)
		(property "Value" "SCD01U16V1KX-GP"
			(at 2.8321 -1.7399 270)
			(unlocked yes)
			(layer "B.Fab")
			(hide yes)
			(effects
				(font
					(size 1.016 1.016)
					(thickness 0.1524)
				)
				(justify mirror)
			)
		)
		(property "Device Type" "C0201H13"
			(at 2.8321 -3.2639 270)
			(unlocked yes)
			(layer "B.Fab")
			(hide yes)
			(effects
				(font
					(size 1.016 1.016)
					(thickness 0.1524)
				)
				(justify mirror)
			)
		)
		(duplicate_pad_numbers_are_jumpers no)
		(fp_rect
			(start 0.2794 0.6477)
			(end -0.2794 -0.6477)
			(stroke
				(width 0)
				(type default)
			)
			(fill no)
			(layer "B.CrtYd")
		)
		(fp_rect
			(start 0.2794 0.6477)
			(end -0.2794 -0.6477)
			(stroke
				(width 0)
				(type default)
			)
			(fill no)
			(layer "B.Fab")
		)
		(pad "1" smd custom
			(at 0 -0.2794 90)
			(size 0.0762 0.0762)
			(layers "B.Cu" "B.Mask" "B.Paste")
			(net "PHY_DPB_TO_SCC_2_DN")
			(options
				(clearance outline)
				(anchor circle)
			)
			(primitives
				(gr_poly
					(pts
						(arc
							(start 0.1524 0.127)
							(mid 0.137521 0.162921)
							(end 0.1016 0.1778)
						)
						(arc
							(start -0.1016 0.1778)
							(mid -0.137521 0.162921)
							(end -0.1524 0.127)
						)
						(arc
							(start -0.1524 -0.127)
							(mid -0.137521 -0.162921)
							(end -0.1016 -0.1778)
						)
						(arc
							(start 0.1016 -0.1778)
							(mid 0.137521 -0.162921)
							(end 0.1524 -0.127)
						)
					)
					(width 0)
					(fill yes)
				)
			)
		)
		(pad "2" smd custom
			(at 0 0.2794 90)
			(size 0.0762 0.0762)
			(layers "B.Cu" "B.Mask" "B.Paste")
			(net "PHY_DPB_TO_SCC_C_2_DN")
			(options
				(clearance outline)
				(anchor circle)
			)
			(primitives
				(gr_poly
					(pts
						(arc
							(start 0.1524 0.127)
							(mid 0.137521 0.162921)
							(end 0.1016 0.1778)
						)
						(arc
							(start -0.1016 0.1778)
							(mid -0.137521 0.162921)
							(end -0.1524 0.127)
						)
						(arc
							(start -0.1524 -0.127)
							(mid -0.137521 -0.162921)
							(end -0.1016 -0.1778)
						)
						(arc
							(start 0.1016 -0.1778)
							(mid 0.137521 -0.162921)
							(end 0.1524 -0.127)
						)
					)
					(width 0)
					(fill yes)
				)
			)
		)
	)
	(footprint ""
		(layer "B.Cu")
		(at 116.713 -61.488066)
		(property "Reference" "C220"
			(at 0 0 0)
			(layer "B.SilkS")
			(hide yes)
			(effects
				(font
					(size 1.27 1.27)
				)
				(justify mirror)
			)
		)
		(property "Value" "SCD1U16V2KX-3GP"
			(at -1.1811 -2.7051 0)
			(unlocked yes)
			(layer "B.Fab")
			(hide yes)
			(effects
				(font
					(size 1.016 1.016)
					(thickness 0.1524)
				)
				(justify mirror)
			)
		)
		(property "Device Type" "C402H22"
			(at -1.1811 -4.2291 0)
			(unlocked yes)
			(layer "B.Fab")
			(hide yes)
			(effects
				(font
					(size 1.016 1.016)
					(thickness 0.1524)
				)
				(justify mirror)
			)
		)
		(duplicate_pad_numbers_are_jumpers no)
		(fp_rect
			(start 0.4318 0.9525)
			(end -0.4318 -0.9525)
			(stroke
				(width 0)
				(type default)
			)
			(fill no)
			(layer "B.CrtYd")
		)
		(fp_rect
			(start 0.4318 0.9525)
			(end -0.4318 -0.9525)
			(stroke
				(width 0)
				(type default)
			)
			(fill no)
			(layer "B.Fab")
		)
		(pad "1" smd custom
			(at 0 -0.4445 180)
			(size 0.1524 0.1524)
			(layers "B.Cu" "B.Mask" "B.Paste")
			(net "GB_VDDH")
			(options
				(clearance outline)
				(anchor circle)
			)
			(primitives
				(gr_poly
					(pts
						(arc
							(start 0.3048 0.2032)
							(mid 0.275042 0.275042)
							(end 0.2032 0.3048)
						)
						(arc
							(start -0.2032 0.3048)
							(mid -0.275042 0.275042)
							(end -0.3048 0.2032)
						)
						(arc
							(start -0.3048 -0.2032)
							(mid -0.275042 -0.275042)
							(end -0.2032 -0.3048)
						)
						(arc
							(start 0.2032 -0.3048)
							(mid 0.275042 -0.275042)
							(end 0.3048 -0.2032)
						)
					)
					(width 0)
					(fill yes)
				)
			)
		)
		(pad "2" smd custom
			(at 0 0.4445 180)
			(size 0.1524 0.1524)
			(layers "B.Cu" "B.Mask" "B.Paste")
			(net "GND")
			(options
				(clearance outline)
				(anchor circle)
			)
			(primitives
				(gr_poly
					(pts
						(arc
							(start 0.3048 0.2032)
							(mid 0.275042 0.275042)
							(end 0.2032 0.3048)
						)
						(arc
							(start -0.2032 0.3048)
							(mid -0.275042 0.275042)
							(end -0.3048 0.2032)
						)
						(arc
							(start -0.3048 -0.2032)
							(mid -0.275042 -0.275042)
							(end -0.2032 -0.3048)
						)
						(arc
							(start 0.2032 -0.3048)
							(mid 0.275042 -0.275042)
							(end 0.3048 -0.2032)
						)
					)
					(width 0)
					(fill yes)
				)
			)
		)
	)
)
